# S9S_MB_2U (Grand Teton) — schematic netlist excerpt (pin names and nets, part order shuffled) for the footprints in the layout excerpt that follows; sources: Cadence DE-HDL packaged netlist, KiCad conversion of 03242023_DA0F0TMBIJ0_F0T_Motherboard_J_brd_V01_OCP.brd

J29  SCONN288_ADR50017P130CC  SCONN288_ADR50017-P130CC IO  pkg DDR288S_1-1VXB  page 110
  VIN_BULK0  = P12V_S3_AUX_CPU1_NVDIMM
  RFU0  = TP_CHG_CPU1_DIMM1_FRU_0
  VIN_MGMT  = P3V3_AUX
  HSCL  = I3C_SPD_DDREFGH_CPU1_LVC1_SCL_4
  HSDA  = I3C_SPD_DDREFGH_CPU1_LVC1_SDA
  VSS0  = GND
  DQ0_A  = M_G_CPU1_SA_DQ<0>
  VSS1  = GND
  DQ1_A  = M_G_CPU1_SA_DQ<1>
  VSS2  = GND
  DQS0_A_T  = M_G_CPU1_SA_DQS_DP<0>
  DQS0_A_C  = M_G_CPU1_SA_DQS_DN<0>
  VSS3  = GND
  DQ4_A  = M_G_CPU1_SA_DQ<4>
  VSS4  = GND
  DQ5_A  = M_G_CPU1_SA_DQ<5>
  VSS5  = GND
  DQ8_A  = M_G_CPU1_SA_DQ<8>
  VSS6  = GND
  DQ9_A  = M_G_CPU1_SA_DQ<9>
  VSS7  = GND
  DQS1_A_T  = M_G_CPU1_SA_DQS_DP<1>
  DQS1_A_C  = M_G_CPU1_SA_DQS_DN<1>
  VSS8  = GND
  DQ12_A  = M_G_CPU1_SA_DQ<12>
  VSS9  = GND
  DQ13_A  = M_G_CPU1_SA_DQ<13>
  VSS10  = GND
  DQ16_A  = M_G_CPU1_SA_DQ<16>
  VSS11  = GND
  DQ17_A  = M_G_CPU1_SA_DQ<17>
  VSS12  = GND
  DQS2_A_T  = M_G_CPU1_SA_DQS_DP<2>
  DQS2_A_C  = M_G_CPU1_SA_DQS_DN<2>
  VSS13  = GND
  DQ20_A  = M_G_CPU1_SA_DQ<20>
  VSS14  = GND
  DQ21_A  = M_G_CPU1_SA_DQ<21>
  VSS15  = GND
  DQ24_A  = M_G_CPU1_SA_DQ<24>
  VSS16  = GND
  DQ25_A  = M_G_CPU1_SA_DQ<25>
  VSS17  = GND
  DQS3_A_T  = M_G_CPU1_SA_DQS_DP<3>
  DQS3_A_C  = M_G_CPU1_SA_DQS_DN<3>
  VSS18  = GND
  DQ28_A  = M_G_CPU1_SA_DQ<28>
  VSS19  = GND
  DQ29_A  = M_G_CPU1_SA_DQ<29>
  VSS20  = GND
  CB0_A  = M_G_CPU1_SA_CB<0>
  VSS21  = GND
  CB1_A  = M_G_CPU1_SA_CB<1>
  VSS22  = GND
  DQS4_A_T  = M_G_CPU1_SA_DQS_DP<4>
  DQS4_A_C  = M_G_CPU1_SA_DQS_DN<4>
  VSS23  = GND
  CB4_A  = M_G_CPU1_SA_CB<4>
  VSS24  = GND
  CB5_A  = M_G_CPU1_SA_CB<5>
  VSS25  = GND
  ALERT_N  = M_G_CPU1_ALERT_N
  VSS26  = GND
  CS0_A_N  = M_G_CPU1_SA_CS_N<0>
  VSS27  = GND
  CA0_A  = M_G_CPU1_SA_CA<0>
  VSS28  = GND
  CA2_A  = M_G_CPU1_SA_CA<2>
  VSS29  = GND
  CA4_A  = M_G_CPU1_SA_CA<4>
  VSS30  = GND
  CA6_A  = M_G_CPU1_SA_CA<6>
  VSS31  = GND
  PAR_A  = M_G_CPU1_SA_PAR
  VSS32  = GND
  CA0_B  = M_G_CPU1_SB_CA<0>
  VSS33  = GND
  CA2_B  = M_G_CPU1_SB_CA<2>
  VSS34  = GND
  CA4_B  = M_G_CPU1_SB_CA<4>
  VSS35  = GND
  CA6_B  = M_G_CPU1_SB_CA<6>
  VSS36  = GND
  CS0_B_N  = M_G_CPU1_SB_CS_N<0>
  VSS37  = GND
  \lbd||rsp_a_n\  = M_G_CPU1_SA_RSP<0>
  \lbs||rsp_b_n\  = M_G_CPU1_SB_RSP<0>
  VSS38  = GND
  CB4_B  = M_G_CPU1_SB_CB<4>
  VSS39  = GND
  CB5_B  = M_G_CPU1_SB_CB<5>
  VSS40  = GND
  \dqs9_b_t||tdqs9_b_t||dbi4_b_n\  = M_G_CPU1_SB_DQS_DP<9>
  \dqs9_b_c||tdqs9_b_c\  = M_G_CPU1_SB_DQS_DN<9>
  VSS41  = GND
  CB0_B  = M_G_CPU1_SB_CB<0>
  VSS42  = GND
  CB1_B  = M_G_CPU1_SB_CB<1>
  VSS43  = GND
  DQ0_B  = M_G_CPU1_SB_DQ<0>
  VSS44  = GND
  DQ1_B  = M_G_CPU1_SB_DQ<1>
  VSS45  = GND
  DQS0_B_T  = M_G_CPU1_SB_DQS_DP<0>
  DQS0_B_C  = M_G_CPU1_SB_DQS_DN<0>
  VSS46  = GND
  DQ4_B  = M_G_CPU1_SB_DQ<4>
  VSS47  = GND
  DQ5_B  = M_G_CPU1_SB_DQ<5>
  VSS48  = GND
  DQ8_B  = M_G_CPU1_SB_DQ<8>
  VSS49  = GND
  DQ9_B  = M_G_CPU1_SB_DQ<9>
  VSS50  = GND
  DQS1_B_T  = M_G_CPU1_SB_DQS_DP<1>
  DQS1_B_C  = M_G_CPU1_SB_DQS_DN<1>
  VSS51  = GND
  DQ12_B  = M_G_CPU1_SB_DQ<12>
  VSS52  = GND
  DQ13_B  = M_G_CPU1_SB_DQ<13>
  VSS53  = GND
  DQ16_B  = M_G_CPU1_SB_DQ<16>
  VSS54  = GND
  DQ17_B  = M_G_CPU1_SB_DQ<17>
  VSS55  = GND
  DQS2_B_T  = M_G_CPU1_SB_DQS_DP<2>
  DQS2_B_C  = M_G_CPU1_SB_DQS_DN<2>
  VSS56  = GND
  DQ20_B  = M_G_CPU1_SB_DQ<20>
  VSS57  = GND
  DQ21_B  = M_G_CPU1_SB_DQ<21>
  VSS58  = GND
  DQ24_B  = M_G_CPU1_SB_DQ<24>
  VSS59  = GND
  DQ25_B  = M_G_CPU1_SB_DQ<25>
  VSS60  = GND
  DQS3_B_T  = M_G_CPU1_SB_DQS_DP<3>
  DQS3_B_C  = M_G_CPU1_SB_DQS_DN<3>
  VSS61  = GND
  DQ28_B  = M_G_CPU1_SB_DQ<28>
  VSS62  = GND
  DQ29_B  = M_G_CPU1_SB_DQ<29>
  VSS63  = GND
  RFU1  = TP_CHG_CPU1_DIMM1_FRU_1
  VIN_BULK1  = P12V_S3_AUX_CPU1_NVDIMM
  VIN_BULK2  = P12V_S3_AUX_CPU1_NVDIMM
  \pwr_good||fail_n\  = PWRGD_CHG_CPU1_DIMM1
  HSA  = PD_CHG_CPU1_DIMM1_SAA
  RFU2  = TP_CHG_CPU1_DIMM1_FRU_2
  RFU3  = TP_CHG_CPU1_DIMM1_FRU_3
  VSS64  = GND
  DQ2_A  = M_G_CPU1_SA_DQ<2>
  VSS65  = GND
  DQ3_A  = M_G_CPU1_SA_DQ<3>
  VSS66  = GND
  \dqs5_a_c||tdqs5_a_c||dqs5_a_t||tdqs5_a_t\  = M_G_CPU1_SA_DQS_DN<5>
  \dqs5_a_t||tdqs5_a_t\  = M_G_CPU1_SA_DQS_DP<5>
  VSS67  = GND
  DQ6_A  = M_G_CPU1_SA_DQ<6>
  VSS68  = GND
  DQ7_A  = M_G_CPU1_SA_DQ<7>
  VSS69  = GND
  DQ10_A  = M_G_CPU1_SA_DQ<10>
  VSS70  = GND
  DQ11_A  = M_G_CPU1_SA_DQ<11>
  VSS71  = GND
  \dqs6_a_c||tdqs6_a_c||dqs6_a_t||tdqs6_a_t\  = M_G_CPU1_SA_DQS_DN<6>
  \dqs6_a_t||tdqs6_a_t\  = M_G_CPU1_SA_DQS_DP<6>
  VSS72  = GND
  DQ14_A  = M_G_CPU1_SA_DQ<14>
  VSS73  = GND
  DQ15_A  = M_G_CPU1_SA_DQ<15>
  VSS74  = GND
  DQ18_A  = M_G_CPU1_SA_DQ<18>
  VSS75  = GND
  DQ19_A  = M_G_CPU1_SA_DQ<19>
  VSS76  = GND
  \dqs7_a_c||tdqs7_a_c\  = M_G_CPU1_SA_DQS_DN<7>
  \dqs7_a_t||tdqs7_a_t\  = M_G_CPU1_SA_DQS_DP<7>
  VSS77  = GND
  DQ22_A  = M_G_CPU1_SA_DQ<22>
  VSS78  = GND
  DQ23_A  = M_G_CPU1_SA_DQ<23>
  VSS79  = GND
  DQ26_A  = M_G_CPU1_SA_DQ<26>
  VSS80  = GND
  DQ27_A  = M_G_CPU1_SA_DQ<27>
  VSS81  = GND
  \dqs8_a_c||tdqs8_a_c\  = M_G_CPU1_SA_DQS_DN<8>
  \dqs8_a_t||tdqs8_a_t\  = M_G_CPU1_SA_DQS_DP<8>
  VSS82  = GND
  DQ30_A  = M_G_CPU1_SA_DQ<30>
  VSS83  = GND
  DQ31_A  = M_G_CPU1_SA_DQ<31>
  VSS84  = GND
  CB2_A  = M_G_CPU1_SA_CB<2>
  VSS85  = GND
  CB3_A  = M_G_CPU1_SA_CB<3>
  VSS86  = GND
  \dqs9_a_c||tdqs9_a_c\  = M_G_CPU1_SA_DQS_DN<9>
  \dqs9_a_t||tdqs9_a_t\  = M_G_CPU1_SA_DQS_DP<9>
  VSS87  = GND
  CB6_A  = M_G_CPU1_SA_CB<6>
  VSS88  = GND
  CB7_A  = M_G_CPU1_SA_CB<7>
  VSS89  = GND
  RESET_N  = RST_M_GH_CPU1_FPGA_N
  VSS90  = GND
  CS1_A_N  = M_G_CPU1_SA_CS_N<1>
  VSS91  = GND
  CA1_A  = M_G_CPU1_SA_CA<1>
  VSS92  = GND
  CA3_A  = M_G_CPU1_SA_CA<3>
  VSS93  = GND
  CA5_A  = M_G_CPU1_SA_CA<5>
  VSS94  = GND
  CK_T  = M_G_CPU1_CLK_DP<0>
  CK_C  = M_G_CPU1_CLK_DN<0>
  VSS95  = GND
  RFU4  = TP_CHG_CPU1_DIMM1_FRU_4
  CA1_B  = M_G_CPU1_SB_CA<1>
  VSS96  = GND
  CA3_B  = M_G_CPU1_SB_CA<3>
  VSS97  = GND
  CA5_B  = M_G_CPU1_SB_CA<5>
  VSS98  = GND
  PAR_B  = M_G_CPU1_SB_PAR
  VSS99  = GND
  CS1_B_N  = M_G_CPU1_SB_CS_N<1>
  VSS100  = GND
  RFU5  = TP_CHG_CPU1_DIMM1_FRU_5
  RFU6  = TP_CHG_CPU1_DIMM1_FRU_6
  VSS101  = GND
  CB6_B  = M_G_CPU1_SB_CB<6>
  VSS102  = GND
  CB7_B  = M_G_CPU1_SB_CB<7>
  VSS103  = GND
  DQS4_B_C  = M_G_CPU1_SB_DQS_DN<4>
  DQS4_B_T  = M_G_CPU1_SB_DQS_DP<4>
  VSS104  = GND
  CB2_B  = M_G_CPU1_SB_CB<2>
  VSS105  = GND
  CB3_B  = M_G_CPU1_SB_CB<3>
  VSS106  = GND
  DQ2_B  = M_G_CPU1_SB_DQ<2>
  VSS107  = GND
  DQ3_B  = M_G_CPU1_SB_DQ<3>
  VSS108  = GND
  \dqs5_b_c||tdqs5_b_c\  = M_G_CPU1_SB_DQS_DN<5>
  \dqs5_b_t||tdqs5_b_t\  = M_G_CPU1_SB_DQS_DP<5>
  VSS109  = GND
  DQ6_B  = M_G_CPU1_SB_DQ<6>
  VSS110  = GND
  DQ7_B  = M_G_CPU1_SB_DQ<7>
  VSS111  = GND
  DQ10_B  = M_G_CPU1_SB_DQ<10>
  VSS112  = GND
  DQ11_B  = M_G_CPU1_SB_DQ<11>
  VSS113  = GND
  \dqs6_b_c||tdqs6_b_c\  = M_G_CPU1_SB_DQS_DN<6>
  \dqs6_b_t||tdqs6_b_t\  = M_G_CPU1_SB_DQS_DP<6>
  VSS114  = GND
  DQ14_B  = M_G_CPU1_SB_DQ<14>
  VSS115  = GND
  DQ15_B  = M_G_CPU1_SB_DQ<15>
  VSS116  = GND
  DQ18_B  = M_G_CPU1_SB_DQ<18>
  VSS117  = GND
  DQ19_B  = M_G_CPU1_SB_DQ<19>
  VSS118  = GND
  \dqs7_b_c||tdqs7_b_c\  = M_G_CPU1_SB_DQS_DN<7>
  \dqs7_b_t||tdqs7_b_t\  = M_G_CPU1_SB_DQS_DP<7>
  VSS119  = GND
  DQ22_B  = M_G_CPU1_SB_DQ<22>
  VSS120  = GND
  DQ23_B  = M_G_CPU1_SB_DQ<23>
  VSS121  = GND
  DQ26_B  = M_G_CPU1_SB_DQ<26>
  VSS122  = GND
  DQ27_B  = M_G_CPU1_SB_DQ<27>
  VSS123  = GND
  \dqs8_b_c||tdqs8_b_c\  = M_G_CPU1_SB_DQS_DN<8>
  \dqs8_b_t||tdqs8_b_t\  = M_G_CPU1_SB_DQS_DP<8>
  VSS124  = GND
  DQ30_B  = M_G_CPU1_SB_DQ<30>
  VSS125  = GND
  DQ31_B  = M_G_CPU1_SB_DQ<31>
  VSS126  = GND
  G1  = GND
  G2  = GND
  G3  = GND

(kicad_pcb
	(version 20260206)
	(generator "pcbnew")
	(generator_version "10.0")
	(general
		(thickness 1.6)
		(legacy_teardrops no)
	)
	(paper "A4")
	(title_block
		(title "03242023_DA0F0TMBIJ0_F0T_Motherboard_J_brd_V01_OCP.brd")
		(comment 1 "Grand Teton / footprint 2874 of 6105 (J29), pads 229-274 of 291")
	)
	(layers
		(0 "F.Cu" signal "TOP")
		(4 "In1.Cu" signal "GND")
		(6 "In2.Cu" signal "IN1")
		(8 "In3.Cu" signal "GND1")
		(10 "In4.Cu" signal "IN2")
		(12 "In5.Cu" signal "GND2")
		(14 "In6.Cu" signal "IN3")
		(16 "In7.Cu" signal "GND3")
		(18 "In8.Cu" signal "VCC")
		(20 "In9.Cu" signal "VCC1")
		(22 "In10.Cu" signal "GND4")
		(24 "In11.Cu" signal "IN4")
		(26 "In12.Cu" signal "GND5")
		(28 "In13.Cu" signal "IN5")
		(30 "In14.Cu" signal "GND6")
		(32 "In15.Cu" signal "IN6")
		(34 "In16.Cu" signal "GND7")
		(2 "B.Cu" signal "BOTTOM")
		(9 "F.Adhes" user "F.Adhesive")
		(11 "B.Adhes" user "B.Adhesive")
		(13 "F.Paste" user "Package Geometry/Pastemask Top")
		(15 "B.Paste" user "Package Geometry/Pastemask Bottom")
		(5 "F.SilkS" user "Ref Des/Silkscreen Top")
		(7 "B.SilkS" user "Ref Des/Silkscreen Bottom")
		(1 "F.Mask" user "Board Geometry/Soldermask Top")
		(3 "B.Mask" user "Board Geometry/Soldermask Bottom")
		(17 "Dwgs.User" user "User.Drawings")
		(19 "Cmts.User" user "User.Comments")
		(21 "Eco1.User" user "User.Eco1")
		(23 "Eco2.User" user "User.Eco2")
		(25 "Edge.Cuts" user "Board Geometry/Outline")
		(27 "Margin" user)
		(31 "F.CrtYd" user "Package Geometry/Place Bound Top")
		(29 "B.CrtYd" user "Package Geometry/Place Bound Bottom")
		(35 "F.Fab" user "Ref Des/Assembly Top")
		(33 "B.Fab" user "Ref Des/Assembly Bottom")
	)
	(footprint ""
		(layer "F.Cu")
		(at 198.58228 -258.091686)
		(property "Reference" "J29"
			(at -3.683 -81.702148 0)
			(unlocked yes)
			(layer "F.SilkS")
			(effects
				(font
					(size 0.7874 0.5842)
					(thickness 0.1524)
				)
				(justify left)
			)
		)
		(property "Value" ""
			(at 0 0 0)
			(layer "F.Fab")
			(effects
				(font
					(size 1.27 1.27)
				)
			)
		)
		(duplicate_pad_numbers_are_jumpers no)
		(pad "229" smd rect
			(at 2.050034 13.17498 270)
			(size 0.519938 1.4986)
			(layers "F.Cu" "F.Mask" "F.Paste")
			(net "M_G_CPU1_SB_CS_N<1>")
		)
		(pad "230" smd rect
			(at 2.050034 14.025118 270)
			(size 0.519938 1.4986)
			(layers "F.Cu" "F.Mask" "F.Paste")
			(net "GND")
		)
		(pad "231" smd rect
			(at 2.050034 14.875002 270)
			(size 0.519938 1.4986)
			(layers "F.Cu" "F.Mask" "F.Paste")
			(net "TP_CHG_CPU1_DIMM1_FRU_5")
		)
		(pad "232" smd rect
			(at 2.050034 15.724886 270)
			(size 0.519938 1.4986)
			(layers "F.Cu" "F.Mask" "F.Paste")
			(net "TP_CHG_CPU1_DIMM1_FRU_6")
		)
		(pad "233" smd rect
			(at 2.050034 16.575024 270)
			(size 0.519938 1.4986)
			(layers "F.Cu" "F.Mask" "F.Paste")
			(net "GND")
		)
		(pad "234" smd rect
			(at 2.050034 17.424908 270)
			(size 0.519938 1.4986)
			(layers "F.Cu" "F.Mask" "F.Paste")
			(net "M_G_CPU1_SB_CB<6>")
		)
		(pad "235" smd rect
			(at 2.050034 18.275046 270)
			(size 0.519938 1.4986)
			(layers "F.Cu" "F.Mask" "F.Paste")
			(net "GND")
		)
		(pad "236" smd rect
			(at 2.050034 19.12493 270)
			(size 0.519938 1.4986)
			(layers "F.Cu" "F.Mask" "F.Paste")
			(net "M_G_CPU1_SB_CB<7>")
		)
		(pad "237" smd rect
			(at 2.050034 19.975068 270)
			(size 0.519938 1.4986)
			(layers "F.Cu" "F.Mask" "F.Paste")
			(net "GND")
		)
		(pad "238" smd rect
			(at 2.050034 20.824952 270)
			(size 0.519938 1.4986)
			(layers "F.Cu" "F.Mask" "F.Paste")
			(net "M_G_CPU1_SB_DQS_DN<4>")
		)
		(pad "239" smd rect
			(at 2.050034 21.67509 270)
			(size 0.519938 1.4986)
			(layers "F.Cu" "F.Mask" "F.Paste")
			(net "M_G_CPU1_SB_DQS_DP<4>")
		)
		(pad "240" smd rect
			(at 2.050034 22.524974 270)
			(size 0.519938 1.4986)
			(layers "F.Cu" "F.Mask" "F.Paste")
			(net "GND")
		)
		(pad "241" smd rect
			(at 2.050034 23.375112 270)
			(size 0.519938 1.4986)
			(layers "F.Cu" "F.Mask" "F.Paste")
			(net "M_G_CPU1_SB_CB<2>")
		)
		(pad "242" smd rect
			(at 2.050034 24.224996 270)
			(size 0.519938 1.4986)
			(layers "F.Cu" "F.Mask" "F.Paste")
			(net "GND")
		)
		(pad "243" smd rect
			(at 2.050034 25.07488 270)
			(size 0.519938 1.4986)
			(layers "F.Cu" "F.Mask" "F.Paste")
			(net "M_G_CPU1_SB_CB<3>")
		)
		(pad "244" smd rect
			(at 2.050034 25.925018 270)
			(size 0.519938 1.4986)
			(layers "F.Cu" "F.Mask" "F.Paste")
			(net "GND")
		)
		(pad "245" smd rect
			(at 2.050034 26.774902 270)
			(size 0.519938 1.4986)
			(layers "F.Cu" "F.Mask" "F.Paste")
			(net "M_G_CPU1_SB_DQ<2>")
		)
		(pad "246" smd rect
			(at 2.050034 27.62504 270)
			(size 0.519938 1.4986)
			(layers "F.Cu" "F.Mask" "F.Paste")
			(net "GND")
		)
		(pad "247" smd rect
			(at 2.050034 28.474924 270)
			(size 0.519938 1.4986)
			(layers "F.Cu" "F.Mask" "F.Paste")
			(net "M_G_CPU1_SB_DQ<3>")
		)
		(pad "248" smd rect
			(at 2.050034 29.325062 270)
			(size 0.519938 1.4986)
			(layers "F.Cu" "F.Mask" "F.Paste")
			(net "GND")
		)
		(pad "249" smd rect
			(at 2.050034 30.174946 270)
			(size 0.519938 1.4986)
			(layers "F.Cu" "F.Mask" "F.Paste")
			(net "M_G_CPU1_SB_DQS_DN<5>")
		)
		(pad "250" smd rect
			(at 2.050034 31.025084 270)
			(size 0.519938 1.4986)
			(layers "F.Cu" "F.Mask" "F.Paste")
			(net "M_G_CPU1_SB_DQS_DP<5>")
		)
		(pad "251" smd rect
			(at 2.050034 31.874968 270)
			(size 0.519938 1.4986)
			(layers "F.Cu" "F.Mask" "F.Paste")
			(net "GND")
		)
		(pad "252" smd rect
			(at 2.050034 32.725106 270)
			(size 0.519938 1.4986)
			(layers "F.Cu" "F.Mask" "F.Paste")
			(net "M_G_CPU1_SB_DQ<6>")
		)
		(pad "253" smd rect
			(at 2.050034 33.57499 270)
			(size 0.519938 1.4986)
			(layers "F.Cu" "F.Mask" "F.Paste")
			(net "GND")
		)
		(pad "254" smd rect
			(at 2.050034 34.425128 270)
			(size 0.519938 1.4986)
			(layers "F.Cu" "F.Mask" "F.Paste")
			(net "M_G_CPU1_SB_DQ<7>")
		)
		(pad "255" smd rect
			(at 2.050034 35.275012 270)
			(size 0.519938 1.4986)
			(layers "F.Cu" "F.Mask" "F.Paste")
			(net "GND")
		)
		(pad "256" smd rect
			(at 2.050034 36.124896 270)
			(size 0.519938 1.4986)
			(layers "F.Cu" "F.Mask" "F.Paste")
			(net "M_G_CPU1_SB_DQ<10>")
		)
		(pad "257" smd rect
			(at 2.050034 36.975034 270)
			(size 0.519938 1.4986)
			(layers "F.Cu" "F.Mask" "F.Paste")
			(net "GND")
		)
		(pad "258" smd rect
			(at 2.050034 37.824918 270)
			(size 0.519938 1.4986)
			(layers "F.Cu" "F.Mask" "F.Paste")
			(net "M_G_CPU1_SB_DQ<11>")
		)
		(pad "259" smd rect
			(at 2.050034 38.675056 270)
			(size 0.519938 1.4986)
			(layers "F.Cu" "F.Mask" "F.Paste")
			(net "GND")
		)
		(pad "260" smd rect
			(at 2.050034 39.52494 270)
			(size 0.519938 1.4986)
			(layers "F.Cu" "F.Mask" "F.Paste")
			(net "M_G_CPU1_SB_DQS_DN<6>")
		)
		(pad "261" smd rect
			(at 2.050034 40.375078 270)
			(size 0.519938 1.4986)
			(layers "F.Cu" "F.Mask" "F.Paste")
			(net "M_G_CPU1_SB_DQS_DP<6>")
		)
		(pad "262" smd rect
			(at 2.050034 41.224962 270)
			(size 0.519938 1.4986)
			(layers "F.Cu" "F.Mask" "F.Paste")
			(net "GND")
		)
		(pad "263" smd rect
			(at 2.050034 42.0751 270)
			(size 0.519938 1.4986)
			(layers "F.Cu" "F.Mask" "F.Paste")
			(net "M_G_CPU1_SB_DQ<14>")
		)
		(pad "264" smd rect
			(at 2.050034 42.924984 270)
			(size 0.519938 1.4986)
			(layers "F.Cu" "F.Mask" "F.Paste")
			(net "GND")
		)
		(pad "265" smd rect
			(at 2.050034 43.775122 270)
			(size 0.519938 1.4986)
			(layers "F.Cu" "F.Mask" "F.Paste")
			(net "M_G_CPU1_SB_DQ<15>")
		)
		(pad "266" smd rect
			(at 2.050034 44.625006 270)
			(size 0.519938 1.4986)
			(layers "F.Cu" "F.Mask" "F.Paste")
			(net "GND")
		)
		(pad "267" smd rect
			(at 2.050034 45.47489 270)
			(size 0.519938 1.4986)
			(layers "F.Cu" "F.Mask" "F.Paste")
			(net "M_G_CPU1_SB_DQ<18>")
		)
		(pad "268" smd rect
			(at 2.050034 46.325028 270)
			(size 0.519938 1.4986)
			(layers "F.Cu" "F.Mask" "F.Paste")
			(net "GND")
		)
		(pad "269" smd rect
			(at 2.050034 47.174912 270)
			(size 0.519938 1.4986)
			(layers "F.Cu" "F.Mask" "F.Paste")
			(net "M_G_CPU1_SB_DQ<19>")
		)
		(pad "270" smd rect
			(at 2.050034 48.02505 270)
			(size 0.519938 1.4986)
			(layers "F.Cu" "F.Mask" "F.Paste")
			(net "GND")
		)
		(pad "271" smd rect
			(at 2.050034 48.874934 270)
			(size 0.519938 1.4986)
			(layers "F.Cu" "F.Mask" "F.Paste")
			(net "M_G_CPU1_SB_DQS_DN<7>")
		)
		(pad "272" smd rect
			(at 2.050034 49.725072 270)
			(size 0.519938 1.4986)
			(layers "F.Cu" "F.Mask" "F.Paste")
			(net "M_G_CPU1_SB_DQS_DP<7>")
		)
		(pad "273" smd rect
			(at 2.050034 50.574956 270)
			(size 0.519938 1.4986)
			(layers "F.Cu" "F.Mask" "F.Paste")
			(net "GND")
		)
		(pad "274" smd rect
			(at 2.050034 51.425094 270)
			(size 0.519938 1.4986)
			(layers "F.Cu" "F.Mask" "F.Paste")
			(net "M_G_CPU1_SB_DQ<22>")
		)
	)
)
